# SCM (Grand Teton) — schematic netlist excerpt (pin names and nets, part order shuffled) for the footprints in the layout excerpt that follows; sources: Cadence DE-HDL packaged netlist, KiCad conversion of 12092022_DA0F0TMDCD0_F0T_Management_Board_D_brd_V3_OCP.brd

R856  Q_RES  4.7K 1% CHIP  pkg 0402LF  page 14 : A = P1V8_AUX ; B = FM_BOARD_BMC_REV_ID1

(kicad_pcb
	(version 20260206)
	(generator "pcbnew")
	(generator_version "10.0")
	(general
		(thickness 1.6)
		(legacy_teardrops no)
	)
	(paper "A4")
	(title_block
		(title "12092022_DA0F0TMDCD0_F0T_Management_Board_D_brd_V3_OCP.brd")
		(comment 1 "Grand Teton / footprints 632-632 of 1440")
	)
	(layers
		(0 "F.Cu" signal "TOP")
		(4 "In1.Cu" signal "GND")
		(6 "In2.Cu" signal "IN1")
		(8 "In3.Cu" signal "GND1")
		(10 "In4.Cu" signal "IN2")
		(12 "In5.Cu" signal "VCC")
		(14 "In6.Cu" signal "VCC1")
		(16 "In7.Cu" signal "IN3")
		(18 "In8.Cu" signal "GND2")
		(20 "In9.Cu" signal "IN4")
		(22 "In10.Cu" signal "GND3")
		(2 "B.Cu" signal "BOTTOM")
		(9 "F.Adhes" user "F.Adhesive")
		(11 "B.Adhes" user "B.Adhesive")
		(13 "F.Paste" user "Package Geometry/Pastemask Top")
		(15 "B.Paste" user "Package Geometry/Pastemask Bottom")
		(5 "F.SilkS" user "Ref Des/Silkscreen Top")
		(7 "B.SilkS" user "Ref Des/Silkscreen Bottom")
		(1 "F.Mask" user "Board Geometry/Soldermask Top")
		(3 "B.Mask" user "Board Geometry/Soldermask Bottom")
		(17 "Dwgs.User" user "User.Drawings")
		(19 "Cmts.User" user "User.Comments")
		(21 "Eco1.User" user "User.Eco1")
		(23 "Eco2.User" user "User.Eco2")
		(25 "Edge.Cuts" user "Board Geometry/Outline")
		(27 "Margin" user)
		(31 "F.CrtYd" user "Package Geometry/Place Bound Top")
		(29 "B.CrtYd" user "Package Geometry/Place Bound Bottom")
		(35 "F.Fab" user "Ref Des/Assembly Top")
		(33 "B.Fab" user "Ref Des/Assembly Bottom")
	)
	(footprint ""
		(layer "F.Cu")
		(at 71.374 -19.685 90)
		(property "Reference" "R856"
			(at 0 0 90)
			(layer "F.SilkS")
			(hide yes)
			(effects
				(font
					(size 1.27 1.27)
				)
			)
		)
		(property "Value" ""
			(at 0 0 90)
			(layer "F.Fab")
			(effects
				(font
					(size 1.27 1.27)
				)
			)
		)
		(duplicate_pad_numbers_are_jumpers no)
		(fp_line
			(start 0.7874 -0.4064)
			(end 0.7874 0.4064)
			(stroke
				(width 0.1524)
				(type default)
			)
			(layer "F.SilkS")
		)
		(fp_line
			(start -0.7874 -0.4064)
			(end 0.7874 -0.4064)
			(stroke
				(width 0.1524)
				(type default)
			)
			(layer "F.SilkS")
		)
		(fp_line
			(start 0.7874 0.4064)
			(end -0.7874 0.4064)
			(stroke
				(width 0.1524)
				(type default)
			)
			(layer "F.SilkS")
		)
		(fp_line
			(start -0.7874 0.4064)
			(end -0.7874 -0.4064)
			(stroke
				(width 0.1524)
				(type default)
			)
			(layer "F.SilkS")
		)
		(fp_line
			(start -0.12065 -0.305054)
			(end -0.12065 -0.2794)
			(stroke
				(width 0.1)
				(type default)
			)
			(layer "F.Fab")
		)
		(fp_line
			(start -0.67945 -0.305054)
			(end -0.12065 -0.305054)
			(stroke
				(width 0.1)
				(type default)
			)
			(layer "F.Fab")
		)
		(fp_line
			(start 0.67945 -0.3048)
			(end 0.67945 0.3048)
			(stroke
				(width 0.1)
				(type default)
			)
			(layer "F.Fab")
		)
		(fp_line
			(start 0.12065 -0.3048)
			(end 0.67945 -0.3048)
			(stroke
				(width 0.1)
				(type default)
			)
			(layer "F.Fab")
		)
		(fp_line
			(start 0.12065 -0.2794)
			(end 0.12065 -0.3048)
			(stroke
				(width 0.1)
				(type default)
			)
			(layer "F.Fab")
		)
		(fp_line
			(start -0.12065 -0.2794)
			(end 0.12065 -0.2794)
			(stroke
				(width 0.1)
				(type default)
			)
			(layer "F.Fab")
		)
		(fp_line
			(start 0.120396 0.2794)
			(end -0.12065 0.2794)
			(stroke
				(width 0.1)
				(type default)
			)
			(layer "F.Fab")
		)
		(fp_line
			(start -0.12065 0.2794)
			(end -0.12065 0.3048)
			(stroke
				(width 0.1)
				(type default)
			)
			(layer "F.Fab")
		)
		(fp_line
			(start 0.67945 0.3048)
			(end 0.120396 0.3048)
			(stroke
				(width 0.1)
				(type default)
			)
			(layer "F.Fab")
		)
		(fp_line
			(start 0.120396 0.3048)
			(end 0.120396 0.2794)
			(stroke
				(width 0.1)
				(type default)
			)
			(layer "F.Fab")
		)
		(fp_line
			(start -0.12065 0.3048)
			(end -0.67945 0.3048)
			(stroke
				(width 0.1)
				(type default)
			)
			(layer "F.Fab")
		)
		(fp_line
			(start -0.67945 0.3048)
			(end -0.67945 -0.305054)
			(stroke
				(width 0.1)
				(type default)
			)
			(layer "F.Fab")
		)
		(pad "1" smd circle
			(at -0.40005 0 90)
			(size 0 0)
			(layers "F.Cu" "F.Mask" "F.Paste")
			(net "P1V8_AUX")
		)
		(pad "2" smd circle
			(at 0.40005 0 90)
			(size 0 0)
			(layers "F.Cu" "F.Mask" "F.Paste")
			(net "FM_BOARD_BMC_REV_ID1")
		)
	)
)
